(kicad_pcb
	(version 20260206)
	(generator "pcbnew")
	(generator_version "10.0")
	(general
		(thickness 1.6)
		(legacy_teardrops no)
	)
	(paper "A4")
	(title_block
		(title "12092022_DA0F0TMDCD0_F0T_Management_Board_D_brd_V3_OCP.brd")
		(comment 1 "Grand Teton / footprints 891-896 of 1440")
	)
	(layers
		(0 "F.Cu" signal "TOP")
		(4 "In1.Cu" signal "GND")
		(6 "In2.Cu" signal "IN1")
		(8 "In3.Cu" signal "GND1")
		(10 "In4.Cu" signal "IN2")
		(12 "In5.Cu" signal "VCC")
		(14 "In6.Cu" signal "VCC1")
		(16 "In7.Cu" signal "IN3")
		(18 "In8.Cu" signal "GND2")
		(20 "In9.Cu" signal "IN4")
		(22 "In10.Cu" signal "GND3")
		(2 "B.Cu" signal "BOTTOM")
		(9 "F.Adhes" user "F.Adhesive")
		(11 "B.Adhes" user "B.Adhesive")
		(13 "F.Paste" user "Package Geometry/Pastemask Top")
		(15 "B.Paste" user "Package Geometry/Pastemask Bottom")
		(5 "F.SilkS" user "Ref Des/Silkscreen Top")
		(7 "B.SilkS" user "Ref Des/Silkscreen Bottom")
		(1 "F.Mask" user "Board Geometry/Soldermask Top")
		(3 "B.Mask" user "Board Geometry/Soldermask Bottom")
		(17 "Dwgs.User" user "User.Drawings")
		(19 "Cmts.User" user "User.Comments")
		(21 "Eco1.User" user "User.Eco1")
		(23 "Eco2.User" user "User.Eco2")
		(25 "Edge.Cuts" user "Board Geometry/Outline")
		(27 "Margin" user)
		(31 "F.CrtYd" user "Package Geometry/Place Bound Top")
		(29 "B.CrtYd" user "Package Geometry/Place Bound Bottom")
		(35 "F.Fab" user "Ref Des/Assembly Top")
		(33 "B.Fab" user "Ref Des/Assembly Bottom")
	)
	(footprint ""
		(layer "B.Cu")
		(at 67.029838 -40.87622 90)
		(property "Reference" "C67"
			(at 0 0 90)
			(layer "B.SilkS")
			(hide yes)
			(effects
				(font
					(size 1.27 1.27)
				)
				(justify mirror)
			)
		)
		(property "Value" ""
			(at 0 0 90)
			(layer "B.Fab")
			(effects
				(font
					(size 1.27 1.27)
				)
				(justify mirror)
			)
		)
		(duplicate_pad_numbers_are_jumpers no)
		(fp_line
			(start 0.7874 -0.4064)
			(end -0.7874 -0.4064)
			(stroke
				(width 0.1524)
				(type default)
			)
			(layer "B.SilkS")
		)
		(fp_line
			(start -0.7874 -0.4064)
			(end -0.7874 0.4064)
			(stroke
				(width 0.1524)
				(type default)
			)
			(layer "B.SilkS")
		)
		(fp_line
			(start 0.7874 0.4064)
			(end 0.7874 -0.4064)
			(stroke
				(width 0.1524)
				(type default)
			)
			(layer "B.SilkS")
		)
		(fp_line
			(start -0.7874 0.4064)
			(end 0.7874 0.4064)
			(stroke
				(width 0.1524)
				(type default)
			)
			(layer "B.SilkS")
		)
		(fp_line
			(start 0.67945 -0.305054)
			(end 0.12065 -0.305054)
			(stroke
				(width 0.1)
				(type default)
			)
			(layer "B.Fab")
		)
		(fp_line
			(start 0.12065 -0.305054)
			(end 0.12065 -0.2794)
			(stroke
				(width 0.1)
				(type default)
			)
			(layer "B.Fab")
		)
		(fp_line
			(start -0.12065 -0.3048)
			(end -0.67945 -0.3048)
			(stroke
				(width 0.1)
				(type default)
			)
			(layer "B.Fab")
		)
		(fp_line
			(start -0.67945 -0.3048)
			(end -0.67945 0.3048)
			(stroke
				(width 0.1)
				(type default)
			)
			(layer "B.Fab")
		)
		(fp_line
			(start 0.12065 -0.2794)
			(end -0.12065 -0.2794)
			(stroke
				(width 0.1)
				(type default)
			)
			(layer "B.Fab")
		)
		(fp_line
			(start -0.12065 -0.2794)
			(end -0.12065 -0.3048)
			(stroke
				(width 0.1)
				(type default)
			)
			(layer "B.Fab")
		)
		(fp_line
			(start 0.12065 0.2794)
			(end 0.12065 0.3048)
			(stroke
				(width 0.1)
				(type default)
			)
			(layer "B.Fab")
		)
		(fp_line
			(start -0.120396 0.2794)
			(end 0.12065 0.2794)
			(stroke
				(width 0.1)
				(type default)
			)
			(layer "B.Fab")
		)
		(fp_line
			(start 0.67945 0.3048)
			(end 0.67945 -0.305054)
			(stroke
				(width 0.1)
				(type default)
			)
			(layer "B.Fab")
		)
		(fp_line
			(start 0.12065 0.3048)
			(end 0.67945 0.3048)
			(stroke
				(width 0.1)
				(type default)
			)
			(layer "B.Fab")
		)
		(fp_line
			(start -0.120396 0.3048)
			(end -0.120396 0.2794)
			(stroke
				(width 0.1)
				(type default)
			)
			(layer "B.Fab")
		)
		(fp_line
			(start -0.67945 0.3048)
			(end -0.120396 0.3048)
			(stroke
				(width 0.1)
				(type default)
			)
			(layer "B.Fab")
		)
		(pad "1" smd circle
			(at 0.40005 0 270)
			(size 0 0)
			(layers "B.Cu" "B.Mask" "B.Paste")
			(net "P1V2_STBY_MVDD_CK")
		)
		(pad "2" smd circle
			(at -0.40005 0 270)
			(size 0 0)
			(layers "B.Cu" "B.Mask" "B.Paste")
			(net "GND")
		)
	)
	(footprint ""
		(layer "B.Cu")
		(at 83.16722 -41.506394 180)
		(property "Reference" "R369"
			(at 0 0 0)
			(layer "B.SilkS")
			(hide yes)
			(effects
				(font
					(size 1.27 1.27)
				)
				(justify mirror)
			)
		)
		(property "Value" ""
			(at 0 0 0)
			(layer "B.Fab")
			(effects
				(font
					(size 1.27 1.27)
				)
				(justify mirror)
			)
		)
		(duplicate_pad_numbers_are_jumpers no)
		(fp_line
			(start 0.7874 0.4064)
			(end 0.7874 -0.4064)
			(stroke
				(width 0.1524)
				(type default)
			)
			(layer "B.SilkS")
		)
		(fp_line
			(start 0.7874 -0.4064)
			(end -0.7874 -0.4064)
			(stroke
				(width 0.1524)
				(type default)
			)
			(layer "B.SilkS")
		)
		(fp_line
			(start -0.7874 0.4064)
			(end 0.7874 0.4064)
			(stroke
				(width 0.1524)
				(type default)
			)
			(layer "B.SilkS")
		)
		(fp_line
			(start -0.7874 -0.4064)
			(end -0.7874 0.4064)
			(stroke
				(width 0.1524)
				(type default)
			)
			(layer "B.SilkS")
		)
		(fp_line
			(start 0.67945 0.3048)
			(end 0.67945 -0.305054)
			(stroke
				(width 0.1)
				(type default)
			)
			(layer "B.Fab")
		)
		(fp_line
			(start 0.67945 -0.305054)
			(end 0.12065 -0.305054)
			(stroke
				(width 0.1)
				(type default)
			)
			(layer "B.Fab")
		)
		(fp_line
			(start 0.12065 0.3048)
			(end 0.67945 0.3048)
			(stroke
				(width 0.1)
				(type default)
			)
			(layer "B.Fab")
		)
		(fp_line
			(start 0.12065 0.2794)
			(end 0.12065 0.3048)
			(stroke
				(width 0.1)
				(type default)
			)
			(layer "B.Fab")
		)
		(fp_line
			(start 0.12065 -0.2794)
			(end -0.12065 -0.2794)
			(stroke
				(width 0.1)
				(type default)
			)
			(layer "B.Fab")
		)
		(fp_line
			(start 0.12065 -0.305054)
			(end 0.12065 -0.2794)
			(stroke
				(width 0.1)
				(type default)
			)
			(layer "B.Fab")
		)
		(fp_line
			(start -0.120396 0.3048)
			(end -0.120396 0.2794)
			(stroke
				(width 0.1)
				(type default)
			)
			(layer "B.Fab")
		)
		(fp_line
			(start -0.120396 0.2794)
			(end 0.12065 0.2794)
			(stroke
				(width 0.1)
				(type default)
			)
			(layer "B.Fab")
		)
		(fp_line
			(start -0.12065 -0.2794)
			(end -0.12065 -0.3048)
			(stroke
				(width 0.1)
				(type default)
			)
			(layer "B.Fab")
		)
		(fp_line
			(start -0.12065 -0.3048)
			(end -0.67945 -0.3048)
			(stroke
				(width 0.1)
				(type default)
			)
			(layer "B.Fab")
		)
		(fp_line
			(start -0.67945 0.3048)
			(end -0.120396 0.3048)
			(stroke
				(width 0.1)
				(type default)
			)
			(layer "B.Fab")
		)
		(fp_line
			(start -0.67945 -0.3048)
			(end -0.67945 0.3048)
			(stroke
				(width 0.1)
				(type default)
			)
			(layer "B.Fab")
		)
		(pad "1" smd circle
			(at 0.40005 0)
			(size 0 0)
			(layers "B.Cu" "B.Mask" "B.Paste")
			(net "M_BMC_DDR4_MACT_N")
		)
		(pad "2" smd circle
			(at -0.40005 0)
			(size 0 0)
			(layers "B.Cu" "B.Mask" "B.Paste")
			(net "P1V2_AUX")
		)
	)
	(footprint ""
		(layer "B.Cu")
		(at 43.053 -6.604 -90)
		(property "Reference" "R84"
			(at 0 0 90)
			(layer "B.SilkS")
			(hide yes)
			(effects
				(font
					(size 1.27 1.27)
				)
				(justify mirror)
			)
		)
		(property "Value" ""
			(at 0 0 90)
			(layer "B.Fab")
			(effects
				(font
					(size 1.27 1.27)
				)
				(justify mirror)
			)
		)
		(duplicate_pad_numbers_are_jumpers no)
		(fp_line
			(start -0.7874 0.4064)
			(end 0.7874 0.4064)
			(stroke
				(width 0.1524)
				(type default)
			)
			(layer "B.SilkS")
		)
		(fp_line
			(start 0.7874 0.4064)
			(end 0.7874 -0.4064)
			(stroke
				(width 0.1524)
				(type default)
			)
			(layer "B.SilkS")
		)
		(fp_line
			(start -0.7874 -0.4064)
			(end -0.7874 0.4064)
			(stroke
				(width 0.1524)
				(type default)
			)
			(layer "B.SilkS")
		)
		(fp_line
			(start 0.7874 -0.4064)
			(end -0.7874 -0.4064)
			(stroke
				(width 0.1524)
				(type default)
			)
			(layer "B.SilkS")
		)
		(fp_line
			(start -0.67945 0.3048)
			(end -0.120396 0.3048)
			(stroke
				(width 0.1)
				(type default)
			)
			(layer "B.Fab")
		)
		(fp_line
			(start -0.120396 0.3048)
			(end -0.120396 0.2794)
			(stroke
				(width 0.1)
				(type default)
			)
			(layer "B.Fab")
		)
		(fp_line
			(start 0.12065 0.3048)
			(end 0.67945 0.3048)
			(stroke
				(width 0.1)
				(type default)
			)
			(layer "B.Fab")
		)
		(fp_line
			(start 0.67945 0.3048)
			(end 0.67945 -0.305054)
			(stroke
				(width 0.1)
				(type default)
			)
			(layer "B.Fab")
		)
		(fp_line
			(start -0.120396 0.2794)
			(end 0.12065 0.2794)
			(stroke
				(width 0.1)
				(type default)
			)
			(layer "B.Fab")
		)
		(fp_line
			(start 0.12065 0.2794)
			(end 0.12065 0.3048)
			(stroke
				(width 0.1)
				(type default)
			)
			(layer "B.Fab")
		)
		(fp_line
			(start -0.12065 -0.2794)
			(end -0.12065 -0.3048)
			(stroke
				(width 0.1)
				(type default)
			)
			(layer "B.Fab")
		)
		(fp_line
			(start 0.12065 -0.2794)
			(end -0.12065 -0.2794)
			(stroke
				(width 0.1)
				(type default)
			)
			(layer "B.Fab")
		)
		(fp_line
			(start -0.67945 -0.3048)
			(end -0.67945 0.3048)
			(stroke
				(width 0.1)
				(type default)
			)
			(layer "B.Fab")
		)
		(fp_line
			(start -0.12065 -0.3048)
			(end -0.67945 -0.3048)
			(stroke
				(width 0.1)
				(type default)
			)
			(layer "B.Fab")
		)
		(fp_line
			(start 0.12065 -0.305054)
			(end 0.12065 -0.2794)
			(stroke
				(width 0.1)
				(type default)
			)
			(layer "B.Fab")
		)
		(fp_line
			(start 0.67945 -0.305054)
			(end 0.12065 -0.305054)
			(stroke
				(width 0.1)
				(type default)
			)
			(layer "B.Fab")
		)
		(pad "1" smd circle
			(at 0.40005 0 90)
			(size 0 0)
			(layers "B.Cu" "B.Mask" "B.Paste")
			(net "V_VGAVS_BUF_R")
		)
		(pad "2" smd circle
			(at -0.40005 0 90)
			(size 0 0)
			(layers "B.Cu" "B.Mask" "B.Paste")
			(net "V_VGAVS_BUF")
		)
	)
	(footprint ""
		(layer "B.Cu")
		(at 76.982828 -46.19879)
		(property "Reference" "R7"
			(at 0 0 0)
			(layer "B.SilkS")
			(hide yes)
			(effects
				(font
					(size 1.27 1.27)
				)
				(justify mirror)
			)
		)
		(property "Value" ""
			(at 0 0 0)
			(layer "B.Fab")
			(effects
				(font
					(size 1.27 1.27)
				)
				(justify mirror)
			)
		)
		(duplicate_pad_numbers_are_jumpers no)
		(fp_line
			(start -0.7874 -0.4064)
			(end -0.7874 0.4064)
			(stroke
				(width 0.1524)
				(type default)
			)
			(layer "B.SilkS")
		)
		(fp_line
			(start -0.7874 0.4064)
			(end 0.7874 0.4064)
			(stroke
				(width 0.1524)
				(type default)
			)
			(layer "B.SilkS")
		)
		(fp_line
			(start 0.487172 -0.4064)
			(end -0.7874 -0.4064)
			(stroke
				(width 0.1524)
				(type default)
			)
			(layer "B.SilkS")
		)
		(fp_line
			(start 0.7874 0.4064)
			(end 0.7874 -0.02921)
			(stroke
				(width 0.1524)
				(type default)
			)
			(layer "B.SilkS")
		)
		(fp_line
			(start -0.67945 -0.3048)
			(end -0.67945 0.3048)
			(stroke
				(width 0.1)
				(type default)
			)
			(layer "B.Fab")
		)
		(fp_line
			(start -0.67945 0.3048)
			(end -0.120396 0.3048)
			(stroke
				(width 0.1)
				(type default)
			)
			(layer "B.Fab")
		)
		(fp_line
			(start -0.12065 -0.3048)
			(end -0.67945 -0.3048)
			(stroke
				(width 0.1)
				(type default)
			)
			(layer "B.Fab")
		)
		(fp_line
			(start -0.12065 -0.2794)
			(end -0.12065 -0.3048)
			(stroke
				(width 0.1)
				(type default)
			)
			(layer "B.Fab")
		)
		(fp_line
			(start -0.120396 0.2794)
			(end 0.12065 0.2794)
			(stroke
				(width 0.1)
				(type default)
			)
			(layer "B.Fab")
		)
		(fp_line
			(start -0.120396 0.3048)
			(end -0.120396 0.2794)
			(stroke
				(width 0.1)
				(type default)
			)
			(layer "B.Fab")
		)
		(fp_line
			(start 0.12065 -0.305054)
			(end 0.12065 -0.2794)
			(stroke
				(width 0.1)
				(type default)
			)
			(layer "B.Fab")
		)
		(fp_line
			(start 0.12065 -0.2794)
			(end -0.12065 -0.2794)
			(stroke
				(width 0.1)
				(type default)
			)
			(layer "B.Fab")
		)
		(fp_line
			(start 0.12065 0.2794)
			(end 0.12065 0.3048)
			(stroke
				(width 0.1)
				(type default)
			)
			(layer "B.Fab")
		)
		(fp_line
			(start 0.12065 0.3048)
			(end 0.67945 0.3048)
			(stroke
				(width 0.1)
				(type default)
			)
			(layer "B.Fab")
		)
		(fp_line
			(start 0.67945 -0.305054)
			(end 0.12065 -0.305054)
			(stroke
				(width 0.1)
				(type default)
			)
			(layer "B.Fab")
		)
		(fp_line
			(start 0.67945 0.3048)
			(end 0.67945 -0.305054)
			(stroke
				(width 0.1)
				(type default)
			)
			(layer "B.Fab")
		)
		(pad "1" smd circle
			(at 0.40005 0 180)
			(size 0 0)
			(layers "B.Cu" "B.Mask" "B.Paste")
			(net "M_BMC_DDR4_MCLK_DN")
		)
		(pad "2" smd circle
			(at -0.40005 0 180)
			(size 0 0)
			(layers "B.Cu" "B.Mask" "B.Paste")
			(net "M_BMC_DDR4_MCLK_C")
		)
	)
	(footprint ""
		(layer "B.Cu")
		(at 21.971 -101.981 90)
		(property "Reference" "R750"
			(at 0 0 90)
			(layer "B.SilkS")
			(hide yes)
			(effects
				(font
					(size 1.27 1.27)
				)
				(justify mirror)
			)
		)
		(property "Value" ""
			(at 0 0 90)
			(layer "B.Fab")
			(effects
				(font
					(size 1.27 1.27)
				)
				(justify mirror)
			)
		)
		(duplicate_pad_numbers_are_jumpers no)
		(fp_line
			(start 0.7874 -0.4064)
			(end -0.7874 -0.4064)
			(stroke
				(width 0.1524)
				(type default)
			)
			(layer "B.SilkS")
		)
		(fp_line
			(start -0.7874 -0.4064)
			(end -0.7874 0.4064)
			(stroke
				(width 0.1524)
				(type default)
			)
			(layer "B.SilkS")
		)
		(fp_line
			(start 0.7874 0.4064)
			(end 0.7874 -0.4064)
			(stroke
				(width 0.1524)
				(type default)
			)
			(layer "B.SilkS")
		)
		(fp_line
			(start -0.7874 0.4064)
			(end 0.7874 0.4064)
			(stroke
				(width 0.1524)
				(type default)
			)
			(layer "B.SilkS")
		)
		(fp_line
			(start 0.67945 -0.305054)
			(end 0.12065 -0.305054)
			(stroke
				(width 0.1)
				(type default)
			)
			(layer "B.Fab")
		)
		(fp_line
			(start 0.12065 -0.305054)
			(end 0.12065 -0.2794)
			(stroke
				(width 0.1)
				(type default)
			)
			(layer "B.Fab")
		)
		(fp_line
			(start -0.12065 -0.3048)
			(end -0.67945 -0.3048)
			(stroke
				(width 0.1)
				(type default)
			)
			(layer "B.Fab")
		)
		(fp_line
			(start -0.67945 -0.3048)
			(end -0.67945 0.3048)
			(stroke
				(width 0.1)
				(type default)
			)
			(layer "B.Fab")
		)
		(fp_line
			(start 0.12065 -0.2794)
			(end -0.12065 -0.2794)
			(stroke
				(width 0.1)
				(type default)
			)
			(layer "B.Fab")
		)
		(fp_line
			(start -0.12065 -0.2794)
			(end -0.12065 -0.3048)
			(stroke
				(width 0.1)
				(type default)
			)
			(layer "B.Fab")
		)
		(fp_line
			(start 0.12065 0.2794)
			(end 0.12065 0.3048)
			(stroke
				(width 0.1)
				(type default)
			)
			(layer "B.Fab")
		)
		(fp_line
			(start -0.120396 0.2794)
			(end 0.12065 0.2794)
			(stroke
				(width 0.1)
				(type default)
			)
			(layer "B.Fab")
		)
		(fp_line
			(start 0.67945 0.3048)
			(end 0.67945 -0.305054)
			(stroke
				(width 0.1)
				(type default)
			)
			(layer "B.Fab")
		)
		(fp_line
			(start 0.12065 0.3048)
			(end 0.67945 0.3048)
			(stroke
				(width 0.1)
				(type default)
			)
			(layer "B.Fab")
		)
		(fp_line
			(start -0.120396 0.3048)
			(end -0.120396 0.2794)
			(stroke
				(width 0.1)
				(type default)
			)
			(layer "B.Fab")
		)
		(fp_line
			(start -0.67945 0.3048)
			(end -0.120396 0.3048)
			(stroke
				(width 0.1)
				(type default)
			)
			(layer "B.Fab")
		)
		(pad "1" smd circle
			(at 0.40005 0 270)
			(size 0 0)
			(layers "B.Cu" "B.Mask" "B.Paste")
			(net "FM_BMC_DEBUG_SW_N")
		)
		(pad "2" smd circle
			(at -0.40005 0 270)
			(size 0 0)
			(layers "B.Cu" "B.Mask" "B.Paste")
			(net "FM_BMC_DEBUG_SW_R2_N")
		)
	)
	(footprint ""
		(layer "B.Cu")
		(at 49.109122 -45.716444 90)
		(property "Reference" "C33"
			(at 0 0 90)
			(layer "B.SilkS")
			(hide yes)
			(effects
				(font
					(size 1.27 1.27)
				)
				(justify mirror)
			)
		)
		(property "Value" ""
			(at 0 0 90)
			(layer "B.Fab")
			(effects
				(font
					(size 1.27 1.27)
				)
				(justify mirror)
			)
		)
		(duplicate_pad_numbers_are_jumpers no)
		(fp_line
			(start 0.7874 -0.4064)
			(end -0.7874 -0.4064)
			(stroke
				(width 0.1524)
				(type default)
			)
			(layer "B.SilkS")
		)
		(fp_line
			(start -0.7874 -0.4064)
			(end -0.7874 0.4064)
			(stroke
				(width 0.1524)
				(type default)
			)
			(layer "B.SilkS")
		)
		(fp_line
			(start 0.7874 0.4064)
			(end 0.7874 -0.4064)
			(stroke
				(width 0.1524)
				(type default)
			)
			(layer "B.SilkS")
		)
		(fp_line
			(start -0.7874 0.4064)
			(end 0.7874 0.4064)
			(stroke
				(width 0.1524)
				(type default)
			)
			(layer "B.SilkS")
		)
		(fp_line
			(start 0.67945 -0.305054)
			(end 0.12065 -0.305054)
			(stroke
				(width 0.1)
				(type default)
			)
			(layer "B.Fab")
		)
		(fp_line
			(start 0.12065 -0.305054)
			(end 0.12065 -0.2794)
			(stroke
				(width 0.1)
				(type default)
			)
			(layer "B.Fab")
		)
		(fp_line
			(start -0.12065 -0.3048)
			(end -0.67945 -0.3048)
			(stroke
				(width 0.1)
				(type default)
			)
			(layer "B.Fab")
		)
		(fp_line
			(start -0.67945 -0.3048)
			(end -0.67945 0.3048)
			(stroke
				(width 0.1)
				(type default)
			)
			(layer "B.Fab")
		)
		(fp_line
			(start 0.12065 -0.2794)
			(end -0.12065 -0.2794)
			(stroke
				(width 0.1)
				(type default)
			)
			(layer "B.Fab")
		)
		(fp_line
			(start -0.12065 -0.2794)
			(end -0.12065 -0.3048)
			(stroke
				(width 0.1)
				(type default)
			)
			(layer "B.Fab")
		)
		(fp_line
			(start 0.12065 0.2794)
			(end 0.12065 0.3048)
			(stroke
				(width 0.1)
				(type default)
			)
			(layer "B.Fab")
		)
		(fp_line
			(start -0.120396 0.2794)
			(end 0.12065 0.2794)
			(stroke
				(width 0.1)
				(type default)
			)
			(layer "B.Fab")
		)
		(fp_line
			(start 0.67945 0.3048)
			(end 0.67945 -0.305054)
			(stroke
				(width 0.1)
				(type default)
			)
			(layer "B.Fab")
		)
		(fp_line
			(start 0.12065 0.3048)
			(end 0.67945 0.3048)
			(stroke
				(width 0.1)
				(type default)
			)
			(layer "B.Fab")
		)
		(fp_line
			(start -0.120396 0.3048)
			(end -0.120396 0.2794)
			(stroke
				(width 0.1)
				(type default)
			)
			(layer "B.Fab")
		)
		(fp_line
			(start -0.67945 0.3048)
			(end -0.120396 0.3048)
			(stroke
				(width 0.1)
				(type default)
			)
			(layer "B.Fab")
		)
		(pad "1" smd circle
			(at 0.40005 0 270)
			(size 0 0)
			(layers "B.Cu" "B.Mask" "B.Paste")
			(net "P3V3_P2V5_P1V8_RVDD")
		)
		(pad "2" smd circle
			(at -0.40005 0 270)
			(size 0 0)
			(layers "B.Cu" "B.Mask" "B.Paste")
			(net "GND")
		)
	)
)
